# T6G (Grand Teton) — schematic netlist excerpt (pin names and nets, part order shuffled) for the footprints in the layout excerpt that follows; sources: Cadence DE-HDL packaged netlist, KiCad conversion of 04192023_DAF0TMB3IC0_F0TG_MB_C_brd_V02_OCP.brd

PR32  Q_RES  0 5% CHIP  pkg 0402LF  page 200 : A = NC_PVDDCR_CPU1_P0_IMON8 ; B = GND
C1826  Q_CAP  0.1UF 25V 10% X7R  pkg 0402  page 138 : A = P3V3_AUX ; B = GND

(kicad_pcb
	(version 20260206)
	(generator "pcbnew")
	(generator_version "10.0")
	(general
		(thickness 1.6)
		(legacy_teardrops no)
	)
	(paper "A4")
	(title_block
		(title "04192023_DAF0TMB3IC0_F0TG_MB_C_brd_V02_OCP.brd")
		(comment 1 "Grand Teton / footprints 6029-6030 of 8354")
	)
	(layers
		(0 "F.Cu" signal "TOP")
		(4 "In1.Cu" signal "GND")
		(6 "In2.Cu" signal "IN1")
		(8 "In3.Cu" signal "GND1")
		(10 "In4.Cu" signal "IN2")
		(12 "In5.Cu" signal "GND2")
		(14 "In6.Cu" signal "IN3")
		(16 "In7.Cu" signal "GND3")
		(18 "In8.Cu" signal "VCC")
		(20 "In9.Cu" signal "VCC1")
		(22 "In10.Cu" signal "GND4")
		(24 "In11.Cu" signal "IN4")
		(26 "In12.Cu" signal "GND5")
		(28 "In13.Cu" signal "IN5")
		(30 "In14.Cu" signal "GND6")
		(32 "In15.Cu" signal "IN6")
		(34 "In16.Cu" signal "GND7")
		(2 "B.Cu" signal "BOTTOM")
		(9 "F.Adhes" user "F.Adhesive")
		(11 "B.Adhes" user "B.Adhesive")
		(13 "F.Paste" user "Package Geometry/Pastemask Top")
		(15 "B.Paste" user "Package Geometry/Pastemask Bottom")
		(5 "F.SilkS" user "Ref Des/Silkscreen Top")
		(7 "B.SilkS" user "Ref Des/Silkscreen Bottom")
		(1 "F.Mask" user "Board Geometry/Soldermask Top")
		(3 "B.Mask" user "Board Geometry/Soldermask Bottom")
		(17 "Dwgs.User" user "User.Drawings")
		(19 "Cmts.User" user "User.Comments")
		(21 "Eco1.User" user "User.Eco1")
		(23 "Eco2.User" user "User.Eco2")
		(25 "Edge.Cuts" user "Board Geometry/Outline")
		(27 "Margin" user)
		(31 "F.CrtYd" user "Package Geometry/Place Bound Top")
		(29 "B.CrtYd" user "Package Geometry/Place Bound Bottom")
		(35 "F.Fab" user "Ref Des/Assembly Top")
		(33 "B.Fab" user "Ref Des/Assembly Bottom")
	)
	(footprint ""
		(layer "B.Cu")
		(at 203.87818 -79.444342)
		(property "Reference" "C1826"
			(at 0 0 0)
			(layer "B.SilkS")
			(hide yes)
			(effects
				(font
					(size 1.27 1.27)
				)
				(justify mirror)
			)
		)
		(property "Value" ""
			(at 0 0 0)
			(layer "B.Fab")
			(effects
				(font
					(size 1.27 1.27)
				)
				(justify mirror)
			)
		)
		(duplicate_pad_numbers_are_jumpers no)
		(fp_line
			(start -0.7874 -0.4064)
			(end -0.7874 0.4064)
			(stroke
				(width 0.1524)
				(type default)
			)
			(layer "B.SilkS")
		)
		(fp_line
			(start -0.7874 0.4064)
			(end 0.7874 0.4064)
			(stroke
				(width 0.1524)
				(type default)
			)
			(layer "B.SilkS")
		)
		(fp_line
			(start 0.7874 -0.4064)
			(end -0.7874 -0.4064)
			(stroke
				(width 0.1524)
				(type default)
			)
			(layer "B.SilkS")
		)
		(fp_line
			(start 0.7874 0.4064)
			(end 0.7874 -0.4064)
			(stroke
				(width 0.1524)
				(type default)
			)
			(layer "B.SilkS")
		)
		(fp_line
			(start -0.67945 -0.3048)
			(end -0.67945 0.3048)
			(stroke
				(width 0.1)
				(type default)
			)
			(layer "B.Fab")
		)
		(fp_line
			(start -0.67945 0.3048)
			(end -0.120396 0.3048)
			(stroke
				(width 0.1)
				(type default)
			)
			(layer "B.Fab")
		)
		(fp_line
			(start -0.12065 -0.3048)
			(end -0.67945 -0.3048)
			(stroke
				(width 0.1)
				(type default)
			)
			(layer "B.Fab")
		)
		(fp_line
			(start -0.12065 -0.2794)
			(end -0.12065 -0.3048)
			(stroke
				(width 0.1)
				(type default)
			)
			(layer "B.Fab")
		)
		(fp_line
			(start -0.120396 0.2794)
			(end 0.12065 0.2794)
			(stroke
				(width 0.1)
				(type default)
			)
			(layer "B.Fab")
		)
		(fp_line
			(start -0.120396 0.3048)
			(end -0.120396 0.2794)
			(stroke
				(width 0.1)
				(type default)
			)
			(layer "B.Fab")
		)
		(fp_line
			(start 0.12065 -0.305054)
			(end 0.12065 -0.2794)
			(stroke
				(width 0.1)
				(type default)
			)
			(layer "B.Fab")
		)
		(fp_line
			(start 0.12065 -0.2794)
			(end -0.12065 -0.2794)
			(stroke
				(width 0.1)
				(type default)
			)
			(layer "B.Fab")
		)
		(fp_line
			(start 0.12065 0.2794)
			(end 0.12065 0.3048)
			(stroke
				(width 0.1)
				(type default)
			)
			(layer "B.Fab")
		)
		(fp_line
			(start 0.12065 0.3048)
			(end 0.67945 0.3048)
			(stroke
				(width 0.1)
				(type default)
			)
			(layer "B.Fab")
		)
		(fp_line
			(start 0.67945 -0.305054)
			(end 0.12065 -0.305054)
			(stroke
				(width 0.1)
				(type default)
			)
			(layer "B.Fab")
		)
		(fp_line
			(start 0.67945 0.3048)
			(end 0.67945 -0.305054)
			(stroke
				(width 0.1)
				(type default)
			)
			(layer "B.Fab")
		)
		(pad "1" smd circle
			(at 0.40005 0 180)
			(size 0 0)
			(layers "B.Cu" "B.Mask" "B.Paste")
			(net "P3V3_AUX")
		)
		(pad "2" smd circle
			(at -0.40005 0 180)
			(size 0 0)
			(layers "B.Cu" "B.Mask" "B.Paste")
			(net "GND")
		)
	)
	(footprint ""
		(layer "B.Cu")
		(at 311.277 -358.14 -90)
		(property "Reference" "PR32"
			(at 0 0 90)
			(layer "B.SilkS")
			(hide yes)
			(effects
				(font
					(size 1.27 1.27)
				)
				(justify mirror)
			)
		)
		(property "Value" ""
			(at 0 0 90)
			(layer "B.Fab")
			(effects
				(font
					(size 1.27 1.27)
				)
				(justify mirror)
			)
		)
		(duplicate_pad_numbers_are_jumpers no)
		(fp_line
			(start -0.7874 0.4064)
			(end 0.7874 0.4064)
			(stroke
				(width 0.1524)
				(type default)
			)
			(layer "B.SilkS")
		)
		(fp_line
			(start 0.7874 0.4064)
			(end 0.7874 -0.4064)
			(stroke
				(width 0.1524)
				(type default)
			)
			(layer "B.SilkS")
		)
		(fp_line
			(start -0.7874 -0.4064)
			(end -0.7874 0.4064)
			(stroke
				(width 0.1524)
				(type default)
			)
			(layer "B.SilkS")
		)
		(fp_line
			(start 0.7874 -0.4064)
			(end -0.7874 -0.4064)
			(stroke
				(width 0.1524)
				(type default)
			)
			(layer "B.SilkS")
		)
		(fp_line
			(start -0.67945 0.3048)
			(end -0.120396 0.3048)
			(stroke
				(width 0.1)
				(type default)
			)
			(layer "B.Fab")
		)
		(fp_line
			(start -0.120396 0.3048)
			(end -0.120396 0.2794)
			(stroke
				(width 0.1)
				(type default)
			)
			(layer "B.Fab")
		)
		(fp_line
			(start 0.12065 0.3048)
			(end 0.67945 0.3048)
			(stroke
				(width 0.1)
				(type default)
			)
			(layer "B.Fab")
		)
		(fp_line
			(start 0.67945 0.3048)
			(end 0.67945 -0.305054)
			(stroke
				(width 0.1)
				(type default)
			)
			(layer "B.Fab")
		)
		(fp_line
			(start -0.120396 0.2794)
			(end 0.12065 0.2794)
			(stroke
				(width 0.1)
				(type default)
			)
			(layer "B.Fab")
		)
		(fp_line
			(start 0.12065 0.2794)
			(end 0.12065 0.3048)
			(stroke
				(width 0.1)
				(type default)
			)
			(layer "B.Fab")
		)
		(fp_line
			(start -0.12065 -0.2794)
			(end -0.12065 -0.3048)
			(stroke
				(width 0.1)
				(type default)
			)
			(layer "B.Fab")
		)
		(fp_line
			(start 0.12065 -0.2794)
			(end -0.12065 -0.2794)
			(stroke
				(width 0.1)
				(type default)
			)
			(layer "B.Fab")
		)
		(fp_line
			(start -0.67945 -0.3048)
			(end -0.67945 0.3048)
			(stroke
				(width 0.1)
				(type default)
			)
			(layer "B.Fab")
		)
		(fp_line
			(start -0.12065 -0.3048)
			(end -0.67945 -0.3048)
			(stroke
				(width 0.1)
				(type default)
			)
			(layer "B.Fab")
		)
		(fp_line
			(start 0.12065 -0.305054)
			(end 0.12065 -0.2794)
			(stroke
				(width 0.1)
				(type default)
			)
			(layer "B.Fab")
		)
		(fp_line
			(start 0.67945 -0.305054)
			(end 0.12065 -0.305054)
			(stroke
				(width 0.1)
				(type default)
			)
			(layer "B.Fab")
		)
		(pad "1" smd circle
			(at 0.40005 0 90)
			(size 0 0)
			(layers "B.Cu" "B.Mask" "B.Paste")
			(net "NC_PVDDCR_CPU1_P0_IMON8")
		)
		(pad "2" smd circle
			(at -0.40005 0 90)
			(size 0 0)
			(layers "B.Cu" "B.Mask" "B.Paste")
			(net "GND")
		)
	)
)
